FILE_TYPE = MULTI_PHYS_TABLE;

PART 'MMBT3904'

{========================================================================================}
:VALUE          | PACK_TYPE | MATERIAL | PART_NUMBER      = STANDARD         | LIFECYCLE        | ENVCOMP | PART_NUMBER   | JEDEC_TYPE  | CLASS | DESCRIPTION                          | HEIGHT   | COMPONENT_TYPE | LEAD_LENGTH | LPID | DAY        ;
{========================================================================================}
 'MMBT3904    ' | 'SMLF'    | 'IC'     | 'BA039040039'(!) = 'End of Design'  | 'Comp-Approve'   | 'YES'   | 'BA039040039' |'SOT23_BEC'| 'IC'  | 'TRANS SMD MMBT3904(40V,200MA)SOT23' | '.044IN' | 'SMALLSMT'     | ''          | ''   | '20100819'
 'MMBT3904    ' | 'SMLF'    | 'EMPTY'  | 'BA039040039'(!) = 'End of Design'  | 'Comp-Approve'   | 'YES'   | 'BA039040039' |'SOT23_BEC'| 'IO'  | 'TRANS SMD MMBT3904(40V,200MA)SOT23' | '.044IN' | 'SMALLSMT'     | ''          | ''   | '20100819'

END_PART

END.

